(kicad_pcb
	(version 20260206)
	(generator "pcbnew")
	(generator_version "10.0")
	(general
		(thickness 1.6)
		(legacy_teardrops no)
	)
	(paper "A4")
	(title_block
		(title "v1-chassis-manager — T6M_CM_d_v01_1031_1645.brd")
		(comment 1 "Open CloudServer (Microsoft) / footprint 845 of 2512 (U43), pads 1-116 of 128")
	)
	(layers
		(0 "F.Cu" signal "TOP")
		(4 "In1.Cu" signal "GND1")
		(6 "In2.Cu" signal "IN1")
		(8 "In3.Cu" signal "VCC1")
		(10 "In4.Cu" signal "VCC2")
		(12 "In5.Cu" signal "GND2")
		(14 "In6.Cu" signal "IN2")
		(16 "In7.Cu" signal "IN3")
		(18 "In8.Cu" signal "GND3")
		(2 "B.Cu" signal "BOTTOM")
		(9 "F.Adhes" user "F.Adhesive")
		(11 "B.Adhes" user "B.Adhesive")
		(13 "F.Paste" user "Package Geometry/Pastemask Top")
		(15 "B.Paste" user "Package Geometry/Pastemask Bottom")
		(5 "F.SilkS" user "Ref Des/Silkscreen Top")
		(7 "B.SilkS" user "Ref Des/Silkscreen Bottom")
		(1 "F.Mask" user "Board Geometry/Soldermask Top")
		(3 "B.Mask" user "Board Geometry/Soldermask Bottom")
		(17 "Dwgs.User" user "User.Drawings")
		(19 "Cmts.User" user "User.Comments")
		(21 "Eco1.User" user "User.Eco1")
		(23 "Eco2.User" user "User.Eco2")
		(25 "Edge.Cuts" user "Board Geometry/Outline")
		(27 "Margin" user)
		(31 "F.CrtYd" user "Package Geometry/Place Bound Top")
		(29 "B.CrtYd" user "Package Geometry/Place Bound Bottom")
		(35 "F.Fab" user "Ref Des/Assembly Top")
		(33 "B.Fab" user "Ref Des/Assembly Bottom")
	)
	(footprint ""
		(layer "F.Cu")
		(at 134.01167 -38.63975 -90)
		(property "Reference" "U43"
			(at -10.673334 -1.474216 0)
			(unlocked yes)
			(layer "F.SilkS")
			(effects
				(font
					(size 0.7874 0.5842)
					(thickness 0.1524)
				)
				(justify left)
			)
		)
		(property "Value" ""
			(at 0 0 270)
			(layer "F.Fab")
			(effects
				(font
					(size 1.27 1.27)
				)
			)
		)
		(duplicate_pad_numbers_are_jumpers no)
		(pad "1" smd rect
			(at -8.560054 -9.249918 180)
			(size 0.2794 1.8034)
			(layers "F.Cu" "F.Mask" "F.Paste")
			(net "UART_DTR_P2_N")
		)
		(pad "2" smd rect
			(at -8.560054 -8.750046 180)
			(size 0.2794 1.8034)
			(layers "F.Cu" "F.Mask" "F.Paste")
			(net "UART_RTS_P2_N")
		)
		(pad "3" smd rect
			(at -8.560054 -8.24992 180)
			(size 0.2794 1.8034)
			(layers "F.Cu" "F.Mask" "F.Paste")
			(net "UART_DSR_P2_N")
		)
		(pad "4" smd rect
			(at -8.560054 -7.750048 180)
			(size 0.2794 1.8034)
			(layers "F.Cu" "F.Mask" "F.Paste")
			(net "P5V_NODE1")
		)
		(pad "5" smd rect
			(at -8.560054 -7.249922 180)
			(size 0.2794 1.8034)
			(layers "F.Cu" "F.Mask" "F.Paste")
			(net "UART_TX_P2")
		)
		(pad "6" smd rect
			(at -8.560054 -6.75005 180)
			(size 0.2794 1.8034)
			(layers "F.Cu" "F.Mask" "F.Paste")
			(net "UART_RX_P2")
		)
		(pad "7" smd rect
			(at -8.560054 -6.249924 180)
			(size 0.2794 1.8034)
			(layers "F.Cu" "F.Mask" "F.Paste")
			(net "Net_1829")
		)
		(pad "8" smd rect
			(at -8.560054 -5.750052 180)
			(size 0.2794 1.8034)
			(layers "F.Cu" "F.Mask" "F.Paste")
			(net "Net_1827")
		)
		(pad "9" smd rect
			(at -8.560054 -5.249926 180)
			(size 0.2794 1.8034)
			(layers "F.Cu" "F.Mask" "F.Paste")
			(net "Net_1830")
		)
		(pad "10" smd rect
			(at -8.560054 -4.750054 180)
			(size 0.2794 1.8034)
			(layers "F.Cu" "F.Mask" "F.Paste")
			(net "Net_1828")
		)
		(pad "11" smd rect
			(at -8.560054 -4.249928 180)
			(size 0.2794 1.8034)
			(layers "F.Cu" "F.Mask" "F.Paste")
			(net "UART_DCD_P3_N")
		)
		(pad "12" smd rect
			(at -8.560054 -3.750056 180)
			(size 0.2794 1.8034)
			(layers "F.Cu" "F.Mask" "F.Paste")
			(net "UART_RI_P3_N")
		)
		(pad "13" smd rect
			(at -8.560054 -3.24993 180)
			(size 0.2794 1.8034)
			(layers "F.Cu" "F.Mask" "F.Paste")
			(net "UART_CTS_P3_N")
		)
		(pad "14" smd rect
			(at -8.560054 -2.750058 180)
			(size 0.2794 1.8034)
			(layers "F.Cu" "F.Mask" "F.Paste")
			(net "UART_DTR_P3_R_N")
		)
		(pad "15" smd rect
			(at -8.560054 -2.249932 180)
			(size 0.2794 1.8034)
			(layers "F.Cu" "F.Mask" "F.Paste")
			(net "GND")
		)
		(pad "16" smd rect
			(at -8.560054 -1.75006 180)
			(size 0.2794 1.8034)
			(layers "F.Cu" "F.Mask" "F.Paste")
			(net "UART_RTS_P3_R_N")
		)
		(pad "17" smd rect
			(at -8.560054 -1.249934 180)
			(size 0.2794 1.8034)
			(layers "F.Cu" "F.Mask" "F.Paste")
			(net "UART_DSR_P3_N")
		)
		(pad "18" smd rect
			(at -8.560054 -0.750062 180)
			(size 0.2794 1.8034)
			(layers "F.Cu" "F.Mask" "F.Paste")
			(net "UART_TX_P3_R")
		)
		(pad "19" smd rect
			(at -8.560054 -0.249936 180)
			(size 0.2794 1.8034)
			(layers "F.Cu" "F.Mask" "F.Paste")
			(net "UART_RX_P3")
		)
		(pad "20" smd rect
			(at -8.560054 0.249936 180)
			(size 0.2794 1.8034)
			(layers "F.Cu" "F.Mask" "F.Paste")
			(net "UART_DCD_P4_N")
		)
		(pad "21" smd rect
			(at -8.560054 0.750062 180)
			(size 0.2794 1.8034)
			(layers "F.Cu" "F.Mask" "F.Paste")
			(net "UART_RI_P4_R_N")
		)
		(pad "22" smd rect
			(at -8.560054 1.249934 180)
			(size 0.2794 1.8034)
			(layers "F.Cu" "F.Mask" "F.Paste")
			(net "UART_CTS_P4_N")
		)
		(pad "23" smd rect
			(at -8.560054 1.75006 180)
			(size 0.2794 1.8034)
			(layers "F.Cu" "F.Mask" "F.Paste")
			(net "UART_DTR_P4_R_N")
		)
		(pad "24" smd rect
			(at -8.560054 2.249932 180)
			(size 0.2794 1.8034)
			(layers "F.Cu" "F.Mask" "F.Paste")
			(net "Net_1835")
		)
		(pad "25" smd rect
			(at -8.560054 2.750058 180)
			(size 0.2794 1.8034)
			(layers "F.Cu" "F.Mask" "F.Paste")
			(net "Net_1834")
		)
		(pad "26" smd rect
			(at -8.560054 3.24993 180)
			(size 0.2794 1.8034)
			(layers "F.Cu" "F.Mask" "F.Paste")
			(net "UART_RTS_P4_R_N")
		)
		(pad "27" smd rect
			(at -8.560054 3.750056 180)
			(size 0.2794 1.8034)
			(layers "F.Cu" "F.Mask" "F.Paste")
			(net "UART_DSR_P4_N")
		)
		(pad "28" smd rect
			(at -8.560054 4.249928 180)
			(size 0.2794 1.8034)
			(layers "F.Cu" "F.Mask" "F.Paste")
			(net "UART_TX_P4_R")
		)
		(pad "29" smd rect
			(at -8.560054 4.750054 180)
			(size 0.2794 1.8034)
			(layers "F.Cu" "F.Mask" "F.Paste")
			(net "UART_DTR_P6_N")
		)
		(pad "30" smd rect
			(at -8.560054 5.249926 180)
			(size 0.2794 1.8034)
			(layers "F.Cu" "F.Mask" "F.Paste")
			(net "Net_1824")
		)
		(pad "31" smd rect
			(at -8.560054 5.750052 180)
			(size 0.2794 1.8034)
			(layers "F.Cu" "F.Mask" "F.Paste")
			(net "UART_RX_P4_BUF")
		)
		(pad "32" smd rect
			(at -8.560054 6.249924 180)
			(size 0.2794 1.8034)
			(layers "F.Cu" "F.Mask" "F.Paste")
			(net "UART_CTS_P5_N")
		)
		(pad "33" smd rect
			(at -8.560054 6.75005 180)
			(size 0.2794 1.8034)
			(layers "F.Cu" "F.Mask" "F.Paste")
			(net "UART_DTR_P5_N")
		)
		(pad "34" smd rect
			(at -8.560054 7.249922 180)
			(size 0.2794 1.8034)
			(layers "F.Cu" "F.Mask" "F.Paste")
			(net "UART_RTS_P5_N")
		)
		(pad "35" smd rect
			(at -8.560054 7.750048 180)
			(size 0.2794 1.8034)
			(layers "F.Cu" "F.Mask" "F.Paste")
			(net "P5V_NODE1")
		)
		(pad "36" smd rect
			(at -8.560054 8.24992 180)
			(size 0.2794 1.8034)
			(layers "F.Cu" "F.Mask" "F.Paste")
			(net "UART_DSR_P5_N")
		)
		(pad "37" smd rect
			(at -8.560054 8.750046 180)
			(size 0.2794 1.8034)
			(layers "F.Cu" "F.Mask" "F.Paste")
			(net "SIO_LRESET_N")
		)
		(pad "38" smd rect
			(at -8.560054 9.249918 180)
			(size 0.2794 1.8034)
			(layers "F.Cu" "F.Mask" "F.Paste")
			(net "SIO_PIN38")
		)
		(pad "39" smd rect
			(at -6.249924 11.560048 270)
			(size 0.2794 1.8034)
			(layers "F.Cu" "F.Mask" "F.Paste")
			(net "IRQ_CPU_NODE1_SERIAL_SIO")
		)
		(pad "40" smd rect
			(at -5.750052 11.560048 270)
			(size 0.2794 1.8034)
			(layers "F.Cu" "F.Mask" "F.Paste")
			(net "LPC_CPU_NODE1_FRAME_SIO_L")
		)
		(pad "41" smd rect
			(at -5.249926 11.560048 270)
			(size 0.2794 1.8034)
			(layers "F.Cu" "F.Mask" "F.Paste")
			(net "LPC_CPU_NODE1_LAD0_SIO")
		)
		(pad "42" smd rect
			(at -4.750054 11.560048 270)
			(size 0.2794 1.8034)
			(layers "F.Cu" "F.Mask" "F.Paste")
			(net "LPC_CPU_NODE1_LAD1_SIO")
		)
		(pad "43" smd rect
			(at -4.249928 11.560048 270)
			(size 0.2794 1.8034)
			(layers "F.Cu" "F.Mask" "F.Paste")
			(net "LPC_CPU_NODE1_LAD2_SIO")
		)
		(pad "44" smd rect
			(at -3.750056 11.560048 270)
			(size 0.2794 1.8034)
			(layers "F.Cu" "F.Mask" "F.Paste")
			(net "LPC_CPU_NODE1_LAD3_SIO")
		)
		(pad "45" smd rect
			(at -3.24993 11.560048 270)
			(size 0.2794 1.8034)
			(layers "F.Cu" "F.Mask" "F.Paste")
			(net "SIO_PIN45")
		)
		(pad "46" smd rect
			(at -2.750058 11.560048 270)
			(size 0.2794 1.8034)
			(layers "F.Cu" "F.Mask" "F.Paste")
			(net "Net_576")
		)
		(pad "47" smd rect
			(at -2.249932 11.560048 270)
			(size 0.2794 1.8034)
			(layers "F.Cu" "F.Mask" "F.Paste")
			(net "SIO_PCICLK33")
		)
		(pad "48" smd rect
			(at -1.75006 11.560048 270)
			(size 0.2794 1.8034)
			(layers "F.Cu" "F.Mask" "F.Paste")
			(net "UART_RX_P5")
		)
		(pad "49" smd rect
			(at -1.249934 11.560048 270)
			(size 0.2794 1.8034)
			(layers "F.Cu" "F.Mask" "F.Paste")
			(net "SIO_CLKIN")
		)
		(pad "50" smd rect
			(at -0.750062 11.560048 270)
			(size 0.2794 1.8034)
			(layers "F.Cu" "F.Mask" "F.Paste")
			(net "GND")
		)
		(pad "51" smd rect
			(at -0.249936 11.560048 270)
			(size 0.2794 1.8034)
			(layers "F.Cu" "F.Mask" "F.Paste")
			(net "SIO_PWROK2")
		)
		(pad "52" smd rect
			(at 0.249936 11.560048 270)
			(size 0.2794 1.8034)
			(layers "F.Cu" "F.Mask" "F.Paste")
			(net "SIO_JTAG_CPLD3_TCK_R")
		)
		(pad "53" smd rect
			(at 0.750062 11.560048 270)
			(size 0.2794 1.8034)
			(layers "F.Cu" "F.Mask" "F.Paste")
			(net "Net_1838")
		)
		(pad "54" smd rect
			(at 1.249934 11.560048 270)
			(size 0.2794 1.8034)
			(layers "F.Cu" "F.Mask" "F.Paste")
			(net "SIO_JTAG_CPLD3_TDO")
		)
		(pad "55" smd rect
			(at 1.75006 11.560048 270)
			(size 0.2794 1.8034)
			(layers "F.Cu" "F.Mask" "F.Paste")
			(net "Net_327")
		)
		(pad "56" smd rect
			(at 2.249932 11.560048 270)
			(size 0.2794 1.8034)
			(layers "F.Cu" "F.Mask" "F.Paste")
			(net "SIO_JTAG_CPLD3_TMS_R")
		)
		(pad "57" smd rect
			(at 2.750058 11.560048 270)
			(size 0.2794 1.8034)
			(layers "F.Cu" "F.Mask" "F.Paste")
			(net "SIO_JTAG_CPLD3_TDI_R")
		)
		(pad "58" smd rect
			(at 3.24993 11.560048 270)
			(size 0.2794 1.8034)
			(layers "F.Cu" "F.Mask" "F.Paste")
			(net "SIO_JTAG_CPLD1_TCK_R")
		)
		(pad "59" smd rect
			(at 3.750056 11.560048 270)
			(size 0.2794 1.8034)
			(layers "F.Cu" "F.Mask" "F.Paste")
			(net "SIO_JTAG_CPLD1_TDI_R")
		)
		(pad "60" smd rect
			(at 4.249928 11.560048 270)
			(size 0.2794 1.8034)
			(layers "F.Cu" "F.Mask" "F.Paste")
			(net "Net_57")
		)
		(pad "61" smd rect
			(at 4.750054 11.560048 270)
			(size 0.2794 1.8034)
			(layers "F.Cu" "F.Mask" "F.Paste")
			(net "SIO_JTAG_CPLD1_TMS_R")
		)
		(pad "62" smd rect
			(at 5.249926 11.560048 270)
			(size 0.2794 1.8034)
			(layers "F.Cu" "F.Mask" "F.Paste")
			(net "Net_1842")
		)
		(pad "63" smd rect
			(at 5.750052 11.560048 270)
			(size 0.2794 1.8034)
			(layers "F.Cu" "F.Mask" "F.Paste")
			(net "Net_1831")
		)
		(pad "64" smd rect
			(at 6.249924 11.560048 270)
			(size 0.2794 1.8034)
			(layers "F.Cu" "F.Mask" "F.Paste")
			(net "Net_1847")
		)
		(pad "65" smd rect
			(at 8.560054 9.249918 180)
			(size 0.2794 1.8034)
			(layers "F.Cu" "F.Mask" "F.Paste")
			(net "Net_1825")
		)
		(pad "66" smd rect
			(at 8.560054 8.750046 180)
			(size 0.2794 1.8034)
			(layers "F.Cu" "F.Mask" "F.Paste")
			(net "UART_TX_P5")
		)
		(pad "67" smd rect
			(at 8.560054 8.24992 180)
			(size 0.2794 1.8034)
			(layers "F.Cu" "F.Mask" "F.Paste")
			(net "SIO_VCCH")
		)
		(pad "68" smd rect
			(at 8.560054 7.750048 180)
			(size 0.2794 1.8034)
			(layers "F.Cu" "F.Mask" "F.Paste")
			(net "SIO_COPEN_N")
		)
		(pad "69" smd rect
			(at 8.560054 7.249922 180)
			(size 0.2794 1.8034)
			(layers "F.Cu" "F.Mask" "F.Paste")
			(net "SIO_VBAT")
		)
		(pad "70" smd rect
			(at 8.560054 6.75005 180)
			(size 0.2794 1.8034)
			(layers "F.Cu" "F.Mask" "F.Paste")
			(net "UART_RI_P5_N")
		)
		(pad "71" smd rect
			(at 8.560054 6.249924 180)
			(size 0.2794 1.8034)
			(layers "F.Cu" "F.Mask" "F.Paste")
			(net "SIO_GPIO47")
		)
		(pad "72" smd rect
			(at 8.560054 5.750052 180)
			(size 0.2794 1.8034)
			(layers "F.Cu" "F.Mask" "F.Paste")
			(net "SIO_PIN72")
		)
		(pad "73" smd rect
			(at 8.560054 5.249926 180)
			(size 0.2794 1.8034)
			(layers "F.Cu" "F.Mask" "F.Paste")
			(net "SIO_PIN73")
		)
		(pad "74" smd rect
			(at 8.560054 4.750054 180)
			(size 0.2794 1.8034)
			(layers "F.Cu" "F.Mask" "F.Paste")
			(net "GND")
		)
		(pad "75" smd rect
			(at 8.560054 4.249928 180)
			(size 0.2794 1.8034)
			(layers "F.Cu" "F.Mask" "F.Paste")
			(net "SIO_PIN75")
		)
		(pad "76" smd rect
			(at 8.560054 3.750056 180)
			(size 0.2794 1.8034)
			(layers "F.Cu" "F.Mask" "F.Paste")
			(net "SIO_PIN76")
		)
		(pad "77" smd rect
			(at 8.560054 3.24993 180)
			(size 0.2794 1.8034)
			(layers "F.Cu" "F.Mask" "F.Paste")
			(net "UART_TX_P6")
		)
		(pad "78" smd rect
			(at 8.560054 2.750058 180)
			(size 0.2794 1.8034)
			(layers "F.Cu" "F.Mask" "F.Paste")
			(net "SIO_PIN78")
		)
		(pad "79" smd rect
			(at 8.560054 2.249932 180)
			(size 0.2794 1.8034)
			(layers "F.Cu" "F.Mask" "F.Paste")
			(net "Net_326")
		)
		(pad "80" smd rect
			(at 8.560054 1.75006 180)
			(size 0.2794 1.8034)
			(layers "F.Cu" "F.Mask" "F.Paste")
			(net "SIO_PIN80")
		)
		(pad "81" smd rect
			(at 8.560054 1.249934 180)
			(size 0.2794 1.8034)
			(layers "F.Cu" "F.Mask" "F.Paste")
			(net "SIO_PIN81")
		)
		(pad "82" smd rect
			(at 8.560054 0.750062 180)
			(size 0.2794 1.8034)
			(layers "F.Cu" "F.Mask" "F.Paste")
			(net "SIO_PIN82")
		)
		(pad "83" smd rect
			(at 8.560054 0.249936 180)
			(size 0.2794 1.8034)
			(layers "F.Cu" "F.Mask" "F.Paste")
			(net "SIO_PIN83")
		)
		(pad "84" smd rect
			(at 8.560054 -0.249936 180)
			(size 0.2794 1.8034)
			(layers "F.Cu" "F.Mask" "F.Paste")
			(net "Net_325")
		)
		(pad "85" smd rect
			(at 8.560054 -0.750062 180)
			(size 0.2794 1.8034)
			(layers "F.Cu" "F.Mask" "F.Paste")
			(net "UART_RTS_P6_N")
		)
		(pad "86" smd rect
			(at 8.560054 -1.249934 180)
			(size 0.2794 1.8034)
			(layers "F.Cu" "F.Mask" "F.Paste")
			(net "GNDA")
		)
		(pad "87" smd rect
			(at 8.560054 -1.75006 180)
			(size 0.2794 1.8034)
			(layers "F.Cu" "F.Mask" "F.Paste")
			(net "UART_RI_P6_N")
		)
		(pad "88" smd rect
			(at 8.560054 -2.249932 180)
			(size 0.2794 1.8034)
			(layers "F.Cu" "F.Mask" "F.Paste")
			(net "Net_1841")
		)
		(pad "89" smd rect
			(at 8.560054 -2.750058 180)
			(size 0.2794 1.8034)
			(layers "F.Cu" "F.Mask" "F.Paste")
			(net "Net_1840")
		)
		(pad "90" smd rect
			(at 8.560054 -3.24993 180)
			(size 0.2794 1.8034)
			(layers "F.Cu" "F.Mask" "F.Paste")
			(net "SIO_VREF")
		)
		(pad "91" smd rect
			(at 8.560054 -3.750056 180)
			(size 0.2794 1.8034)
			(layers "F.Cu" "F.Mask" "F.Paste")
			(net "SIO_JTAG_CPLD1_TDO")
		)
		(pad "92" smd rect
			(at 8.560054 -4.249928 180)
			(size 0.2794 1.8034)
			(layers "F.Cu" "F.Mask" "F.Paste")
			(net "UART_CTS_P6_N")
		)
		(pad "93" smd rect
			(at 8.560054 -4.750054 180)
			(size 0.2794 1.8034)
			(layers "F.Cu" "F.Mask" "F.Paste")
			(net "UART_RX_P6")
		)
		(pad "94" smd rect
			(at 8.560054 -5.249926 180)
			(size 0.2794 1.8034)
			(layers "F.Cu" "F.Mask" "F.Paste")
			(net "Net_1846")
		)
		(pad "95" smd rect
			(at 8.560054 -5.750052 180)
			(size 0.2794 1.8034)
			(layers "F.Cu" "F.Mask" "F.Paste")
			(net "UART_DSR_P6_N")
		)
		(pad "96" smd rect
			(at 8.560054 -6.249924 180)
			(size 0.2794 1.8034)
			(layers "F.Cu" "F.Mask" "F.Paste")
			(net "Net_1845")
		)
		(pad "97" smd rect
			(at 8.560054 -6.75005 180)
			(size 0.2794 1.8034)
			(layers "F.Cu" "F.Mask" "F.Paste")
			(net "Net_1844")
		)
		(pad "98" smd rect
			(at 8.560054 -7.249922 180)
			(size 0.2794 1.8034)
			(layers "F.Cu" "F.Mask" "F.Paste")
			(net "Net_1843")
		)
		(pad "99" smd rect
			(at 8.560054 -7.750048 180)
			(size 0.2794 1.8034)
			(layers "F.Cu" "F.Mask" "F.Paste")
			(net "SIO_AVCC")
		)
		(pad "100" smd rect
			(at 8.560054 -8.24992 180)
			(size 0.2794 1.8034)
			(layers "F.Cu" "F.Mask" "F.Paste")
			(net "Net_1836")
		)
		(pad "101" smd rect
			(at 8.560054 -8.750046 180)
			(size 0.2794 1.8034)
			(layers "F.Cu" "F.Mask" "F.Paste")
			(net "Net_1833")
		)
		(pad "102" smd rect
			(at 8.560054 -9.249918 180)
			(size 0.2794 1.8034)
			(layers "F.Cu" "F.Mask" "F.Paste")
			(net "Net_1823")
		)
		(pad "103" smd rect
			(at 6.249924 -11.560048 270)
			(size 0.2794 1.8034)
			(layers "F.Cu" "F.Mask" "F.Paste")
			(net "Net_1821")
		)
		(pad "104" smd rect
			(at 5.750052 -11.560048 270)
			(size 0.2794 1.8034)
			(layers "F.Cu" "F.Mask" "F.Paste")
			(net "Net_1837")
		)
		(pad "105" smd rect
			(at 5.249926 -11.560048 270)
			(size 0.2794 1.8034)
			(layers "F.Cu" "F.Mask" "F.Paste")
			(net "Net_1832")
		)
		(pad "106" smd rect
			(at 4.750054 -11.560048 270)
			(size 0.2794 1.8034)
			(layers "F.Cu" "F.Mask" "F.Paste")
			(net "Net_1826")
		)
		(pad "107" smd rect
			(at 4.249928 -11.560048 270)
			(size 0.2794 1.8034)
			(layers "F.Cu" "F.Mask" "F.Paste")
			(net "Net_1822")
		)
		(pad "108" smd rect
			(at 3.750056 -11.560048 270)
			(size 0.2794 1.8034)
			(layers "F.Cu" "F.Mask" "F.Paste")
			(net "Net_1839")
		)
		(pad "109" smd rect
			(at 3.24993 -11.560048 270)
			(size 0.2794 1.8034)
			(layers "F.Cu" "F.Mask" "F.Paste")
			(net "SIO_CPLD_RSV3_R")
		)
		(pad "110" smd rect
			(at 2.750058 -11.560048 270)
			(size 0.2794 1.8034)
			(layers "F.Cu" "F.Mask" "F.Paste")
			(net "SIO_CPLD_RSV2_R")
		)
		(pad "111" smd rect
			(at 2.249932 -11.560048 270)
			(size 0.2794 1.8034)
			(layers "F.Cu" "F.Mask" "F.Paste")
			(net "SIO_CPLD_RSV1_R")
		)
		(pad "112" smd rect
			(at 1.75006 -11.560048 270)
			(size 0.2794 1.8034)
			(layers "F.Cu" "F.Mask" "F.Paste")
			(net "CPLD_WDT3_R")
		)
		(pad "113" smd rect
			(at 1.249934 -11.560048 270)
			(size 0.2794 1.8034)
			(layers "F.Cu" "F.Mask" "F.Paste")
			(net "SIO_JTAG_CPLD2_TDI_R")
		)
		(pad "114" smd rect
			(at 0.750062 -11.560048 270)
			(size 0.2794 1.8034)
			(layers "F.Cu" "F.Mask" "F.Paste")
			(net "SIO_JTAG_CPLD2_TMS_R")
		)
		(pad "115" smd rect
			(at 0.249936 -11.560048 270)
			(size 0.2794 1.8034)
			(layers "F.Cu" "F.Mask" "F.Paste")
			(net "SIO_JTAG_CPLD2_TDO")
		)
		(pad "116" smd rect
			(at -0.249936 -11.560048 270)
			(size 0.2794 1.8034)
			(layers "F.Cu" "F.Mask" "F.Paste")
			(net "SIO_JTAG_CPLD2_TCK_R")
		)
	)
)
